(kicad_pcb
	(version 20260206)
	(generator "pcbnew")
	(generator_version "10.0")
	(general
		(thickness 1.6)
		(legacy_teardrops no)
	)
	(paper "A4")
	(title_block
		(title "Wiwynn_Tioga_Pass_MB.brd")
		(comment 1 "Tioga Pass / footprints 4305-4312 of 4770")
	)
	(layers
		(0 "F.Cu" signal "TOP")
		(4 "In1.Cu" signal "L2GND")
		(6 "In2.Cu" signal "L3")
		(8 "In3.Cu" signal "L4GND")
		(10 "In4.Cu" signal "L5")
		(12 "In5.Cu" signal "L6GND")
		(14 "In6.Cu" signal "L7VCC")
		(16 "In7.Cu" signal "L8VCC")
		(18 "In8.Cu" signal "L9GND")
		(20 "In9.Cu" signal "L10")
		(22 "In10.Cu" signal "L11GND")
		(24 "In11.Cu" signal "L12")
		(26 "In12.Cu" signal "L13GND")
		(2 "B.Cu" signal "BOTTOM")
		(9 "F.Adhes" user "F.Adhesive")
		(11 "B.Adhes" user "B.Adhesive")
		(13 "F.Paste" user "Package Geometry/Pastemask Top")
		(15 "B.Paste" user "Package Geometry/Pastemask Bottom")
		(5 "F.SilkS" user "Ref Des/Silkscreen Top")
		(7 "B.SilkS" user "Ref Des/Silkscreen Bottom")
		(1 "F.Mask" user "Board Geometry/Soldermask Top")
		(3 "B.Mask" user "Board Geometry/Soldermask Bottom")
		(17 "Dwgs.User" user "User.Drawings")
		(19 "Cmts.User" user "User.Comments")
		(21 "Eco1.User" user "User.Eco1")
		(23 "Eco2.User" user "User.Eco2")
		(25 "Edge.Cuts" user "Board Geometry/Outline")
		(27 "Margin" user)
		(31 "F.CrtYd" user "Package Geometry/Place Bound Top")
		(29 "B.CrtYd" user "Package Geometry/Place Bound Bottom")
		(35 "F.Fab" user "Ref Des/Assembly Top")
		(33 "B.Fab" user "Ref Des/Assembly Bottom")
	)
	(footprint ""
		(layer "B.Cu")
		(at 197.848728 -92.489782 90)
		(property "Reference" "C6N8"
			(at 0 0 90)
			(layer "B.SilkS")
			(hide yes)
			(effects
				(font
					(size 1.27 1.27)
				)
				(justify mirror)
			)
		)
		(property "Value" ""
			(at 0 0 90)
			(layer "B.Fab")
			(effects
				(font
					(size 1.27 1.27)
				)
				(justify mirror)
			)
		)
		(duplicate_pad_numbers_are_jumpers no)
		(fp_rect
			(start -0.7239 -0.2159)
			(end 0.7239 1.9939)
			(stroke
				(width 0)
				(type default)
			)
			(fill no)
			(layer "B.CrtYd")
		)
		(fp_line
			(start 0.7239 -0.2159)
			(end 0.7239 1.9939)
			(stroke
				(width 0.1)
				(type default)
			)
			(layer "B.Fab")
		)
		(fp_line
			(start -0.7239 -0.2159)
			(end 0.7239 -0.2159)
			(stroke
				(width 0.1)
				(type default)
			)
			(layer "B.Fab")
		)
		(fp_line
			(start 0.7239 1.9939)
			(end -0.7239 1.9939)
			(stroke
				(width 0.1)
				(type default)
			)
			(layer "B.Fab")
		)
		(fp_line
			(start -0.7239 1.9939)
			(end -0.7239 -0.2159)
			(stroke
				(width 0.1)
				(type default)
			)
			(layer "B.Fab")
		)
		(pad "1" smd rect
			(at 0 0 270)
			(size 1.27 1.016)
			(layers "B.Cu" "B.Mask" "B.Paste")
			(net "VR_FET_SW_P12V_STBY_PVCCIN_CPU0")
		)
		(pad "2" smd rect
			(at 0 1.778 270)
			(size 1.27 1.016)
			(layers "B.Cu" "B.Mask" "B.Paste")
			(net "GND")
		)
		(zone
			(layer "B.Cu")
			(hatch none 0.5)
			(connect_pads
				(clearance 0)
			)
			(min_thickness 0.25)
			(keepout
				(tracks not_allowed)
				(vias allowed)
				(pads allowed)
				(copperpour not_allowed)
				(footprints allowed)
			)
			(placement
				(enabled no)
				(sheetname "")
			)
			(fill
				(thermal_gap 0.5)
				(thermal_bridge_width 0.5)
				(island_removal_mode 0)
			)
			(polygon
				(pts
					(xy 198.356728 -91.854782) (xy 199.118728 -91.854782) (xy 199.118728 -93.124782) (xy 198.356728 -93.124782)
				)
			)
		)
	)
	(footprint ""
		(layer "B.Cu")
		(at 245.7196 -27.2034 90)
		(property "Reference" "C5T2"
			(at 0 0 90)
			(layer "B.SilkS")
			(hide yes)
			(effects
				(font
					(size 1.27 1.27)
				)
				(justify mirror)
			)
		)
		(property "Value" ""
			(at 0 0 90)
			(layer "B.Fab")
			(effects
				(font
					(size 1.27 1.27)
				)
				(justify mirror)
			)
		)
		(duplicate_pad_numbers_are_jumpers no)
		(fp_rect
			(start 0.500126 1.598422)
			(end -0.500126 -0.201422)
			(stroke
				(width 0)
				(type default)
			)
			(fill no)
			(layer "B.CrtYd")
		)
		(fp_line
			(start 0.500126 -0.201422)
			(end -0.500126 -0.201422)
			(stroke
				(width 0.1)
				(type default)
			)
			(layer "B.Fab")
		)
		(fp_line
			(start -0.500126 -0.201422)
			(end -0.500126 1.598422)
			(stroke
				(width 0.1)
				(type default)
			)
			(layer "B.Fab")
		)
		(fp_line
			(start 0.500126 1.598422)
			(end 0.500126 -0.201422)
			(stroke
				(width 0.1)
				(type default)
			)
			(layer "B.Fab")
		)
		(fp_line
			(start -0.500126 1.598422)
			(end 0.500126 1.598422)
			(stroke
				(width 0.1)
				(type default)
			)
			(layer "B.Fab")
		)
		(pad "1" smd rect
			(at 0 0)
			(size 0.889 0.9906)
			(layers "B.Cu" "B.Mask" "B.Paste")
			(net "PVDDQ_ABC")
		)
		(pad "2" smd rect
			(at 0 1.397)
			(size 0.889 0.9906)
			(layers "B.Cu" "B.Mask" "B.Paste")
			(net "GND")
		)
		(zone
			(layer "B.Cu")
			(hatch none 0.5)
			(connect_pads
				(clearance 0)
			)
			(min_thickness 0.25)
			(keepout
				(tracks not_allowed)
				(vias allowed)
				(pads allowed)
				(copperpour not_allowed)
				(footprints allowed)
			)
			(placement
				(enabled no)
				(sheetname "")
			)
			(fill
				(thermal_gap 0.5)
				(thermal_bridge_width 0.5)
				(island_removal_mode 0)
			)
			(polygon
				(pts
					(xy 246.6721 -27.6987) (xy 246.1641 -27.6987) (xy 246.1641 -26.7081) (xy 246.6721 -26.7081)
				)
			)
		)
		(zone
			(layer "B.Cu")
			(hatch none 0.5)
			(connect_pads
				(clearance 0)
			)
			(min_thickness 0.25)
			(keepout
				(tracks allowed)
				(vias not_allowed)
				(pads allowed)
				(copperpour not_allowed)
				(footprints allowed)
			)
			(placement
				(enabled no)
				(sheetname "")
			)
			(fill
				(thermal_gap 0.5)
				(thermal_bridge_width 0.5)
				(island_removal_mode 0)
			)
			(polygon
				(pts
					(xy 246.6721 -27.6987) (xy 246.1641 -27.6987) (xy 246.1641 -26.7081) (xy 246.6721 -26.7081)
				)
			)
		)
	)
	(footprint ""
		(layer "B.Cu")
		(at 329.356466 -57.916318)
		(property "Reference" "U4R1"
			(at -2.794 0.87503 0)
			(unlocked yes)
			(layer "B.SilkS")
			(effects
				(font
					(size 0.7874 0.5842)
					(thickness 0.1524)
				)
				(justify left mirror)
			)
		)
		(property "Value" ""
			(at 0 0 0)
			(layer "B.Fab")
			(effects
				(font
					(size 1.27 1.27)
				)
				(justify mirror)
			)
		)
		(duplicate_pad_numbers_are_jumpers no)
		(fp_circle
			(center 0.4699 -0.8382)
			(end 0.5969 -0.8382)
			(stroke
				(width 0.254)
				(type default)
			)
			(fill no)
			(layer "B.SilkS")
		)
		(fp_poly
			(pts
				(xy -0.21463 -0.450088) (xy -1.56337 -0.450088) (xy -1.56337 1.75006) (xy -0.21463 1.75006)
			)
			(stroke
				(width 0)
				(type default)
			)
			(fill no)
			(layer "B.CrtYd")
		)
		(fp_line
			(start -1.56337 -0.450088)
			(end -1.56337 1.75006)
			(stroke
				(width 0.1)
				(type default)
			)
			(layer "B.Fab")
		)
		(fp_line
			(start -1.56337 1.75006)
			(end -0.21463 1.75006)
			(stroke
				(width 0.1)
				(type default)
			)
			(layer "B.Fab")
		)
		(fp_line
			(start -0.21463 -0.450088)
			(end -1.56337 -0.450088)
			(stroke
				(width 0.1)
				(type default)
			)
			(layer "B.Fab")
		)
		(fp_line
			(start -0.21463 1.75006)
			(end -0.21463 -0.450088)
			(stroke
				(width 0.1)
				(type default)
			)
			(layer "B.Fab")
		)
		(fp_circle
			(center 0.4699 -0.8382)
			(end 0.5969 -0.8382)
			(stroke
				(width 0.254)
				(type default)
			)
			(fill no)
			(layer "B.Fab")
		)
		(pad "1" smd rect
			(at 0 0 180)
			(size 1.016 0.381)
			(layers "B.Cu" "B.Mask" "B.Paste")
			(net "FM_CPU0_PKGID1")
		)
		(pad "2" smd rect
			(at 0 0.649986 180)
			(size 1.016 0.381)
			(layers "B.Cu" "B.Mask" "B.Paste")
			(net "P1V8_MCP_CPU0")
		)
		(pad "3" smd rect
			(at 0 1.299972 180)
			(size 1.016 0.381)
			(layers "B.Cu" "B.Mask" "B.Paste")
			(net "GND")
		)
		(pad "4" smd rect
			(at -1.778 1.299972 180)
			(size 1.016 0.381)
			(layers "B.Cu" "B.Mask" "B.Paste")
			(net "JTAG_MCP_CPU0_TDI_R")
		)
		(pad "5" smd rect
			(at -1.778 0 180)
			(size 1.016 0.381)
			(layers "B.Cu" "B.Mask" "B.Paste")
			(net "P3V3_STBY")
		)
	)
	(footprint ""
		(layer "B.Cu")
		(at 180.873654 -150.815548)
		(property "Reference" "C6L4"
			(at 0 0 0)
			(layer "B.SilkS")
			(hide yes)
			(effects
				(font
					(size 1.27 1.27)
				)
				(justify mirror)
			)
		)
		(property "Value" ""
			(at 0 0 0)
			(layer "B.Fab")
			(effects
				(font
					(size 1.27 1.27)
				)
				(justify mirror)
			)
		)
		(duplicate_pad_numbers_are_jumpers no)
		(fp_rect
			(start 0.4953 -0.2032)
			(end -0.4953 1.6002)
			(stroke
				(width 0)
				(type default)
			)
			(fill no)
			(layer "B.CrtYd")
		)
		(fp_line
			(start -0.4953 -0.2032)
			(end -0.4953 1.6002)
			(stroke
				(width 0.1)
				(type default)
			)
			(layer "B.Fab")
		)
		(fp_line
			(start -0.4953 1.6002)
			(end 0.4953 1.6002)
			(stroke
				(width 0.1)
				(type default)
			)
			(layer "B.Fab")
		)
		(fp_line
			(start 0.4953 -0.2032)
			(end -0.4953 -0.2032)
			(stroke
				(width 0.1)
				(type default)
			)
			(layer "B.Fab")
		)
		(fp_line
			(start 0.4953 1.6002)
			(end 0.4953 -0.2032)
			(stroke
				(width 0.1)
				(type default)
			)
			(layer "B.Fab")
		)
		(pad "1" smd rect
			(at 0 0 180)
			(size 0.762 0.889)
			(layers "B.Cu" "B.Mask" "B.Paste")
			(net "PVDDQ_DEF")
		)
		(pad "2" smd rect
			(at 0 1.397 180)
			(size 0.762 0.889)
			(layers "B.Cu" "B.Mask" "B.Paste")
			(net "GND")
		)
		(zone
			(layer "B.Cu")
			(hatch none 0.5)
			(connect_pads
				(clearance 0)
			)
			(min_thickness 0.25)
			(keepout
				(tracks not_allowed)
				(vias allowed)
				(pads allowed)
				(copperpour not_allowed)
				(footprints allowed)
			)
			(placement
				(enabled no)
				(sheetname "")
			)
			(fill
				(thermal_gap 0.5)
				(thermal_bridge_width 0.5)
				(island_removal_mode 0)
			)
			(polygon
				(pts
					(xy 181.254654 -150.371048) (xy 180.492654 -150.371048) (xy 180.492654 -149.863048) (xy 181.254654 -149.863048)
				)
			)
		)
	)
	(footprint ""
		(layer "B.Cu")
		(at 438.604406 -33.101026 90)
		(property "Reference" "R1T28"
			(at 0.8382 -0.67818 90)
			(unlocked yes)
			(layer "B.SilkS")
			(effects
				(font
					(size 0.4064 0.254)
					(thickness 0.1524)
				)
				(justify left mirror)
			)
		)
		(property "Value" ""
			(at 0 0 90)
			(layer "B.Fab")
			(effects
				(font
					(size 1.27 1.27)
				)
				(justify mirror)
			)
		)
		(duplicate_pad_numbers_are_jumpers no)
		(fp_poly
			(pts
				(xy 0.2794 -0.1016) (xy -0.2794 -0.1016) (xy -0.2794 0.9906) (xy 0.2794 0.9906)
			)
			(stroke
				(width 0)
				(type default)
			)
			(fill no)
			(layer "B.CrtYd")
		)
		(fp_line
			(start 0.2794 -0.1016)
			(end 0.2794 0.9906)
			(stroke
				(width 0.1)
				(type default)
			)
			(layer "B.Fab")
		)
		(fp_line
			(start -0.2794 -0.1016)
			(end 0.2794 -0.1016)
			(stroke
				(width 0.1)
				(type default)
			)
			(layer "B.Fab")
		)
		(fp_line
			(start 0.2794 0.9906)
			(end -0.2794 0.9906)
			(stroke
				(width 0.1)
				(type default)
			)
			(layer "B.Fab")
		)
		(fp_line
			(start -0.2794 0.9906)
			(end -0.2794 -0.1016)
			(stroke
				(width 0.1)
				(type default)
			)
			(layer "B.Fab")
		)
		(pad "1" smd rect
			(at 0 0 270)
			(size 0.508 0.508)
			(layers "B.Cu" "B.Mask" "B.Paste")
			(net "BMC_M_CLK_DN")
		)
		(pad "2" smd rect
			(at 0 0.889 270)
			(size 0.508 0.508)
			(layers "B.Cu" "B.Mask" "B.Paste")
			(net "BMC_M_CLK")
		)
		(zone
			(layer "B.Cu")
			(hatch none 0.5)
			(connect_pads
				(clearance 0)
			)
			(min_thickness 0.25)
			(keepout
				(tracks allowed)
				(vias not_allowed)
				(pads allowed)
				(copperpour not_allowed)
				(footprints allowed)
			)
			(placement
				(enabled no)
				(sheetname "")
			)
			(fill
				(thermal_gap 0.5)
				(thermal_bridge_width 0.5)
				(island_removal_mode 0)
			)
			(polygon
				(pts
					(xy 438.858406 -33.355026) (xy 438.858406 -32.847026) (xy 439.239406 -32.847026) (xy 439.239406 -33.355026)
				)
			)
		)
		(zone
			(layer "B.Cu")
			(hatch none 0.5)
			(connect_pads
				(clearance 0)
			)
			(min_thickness 0.25)
			(keepout
				(tracks not_allowed)
				(vias allowed)
				(pads allowed)
				(copperpour not_allowed)
				(footprints allowed)
			)
			(placement
				(enabled no)
				(sheetname "")
			)
			(fill
				(thermal_gap 0.5)
				(thermal_bridge_width 0.5)
				(island_removal_mode 0)
			)
			(polygon
				(pts
					(xy 439.239406 -33.355026) (xy 439.239406 -32.847026) (xy 438.858406 -32.847026) (xy 438.858406 -33.355026)
				)
			)
		)
	)
	(footprint ""
		(layer "B.Cu")
		(at 423.387774 -40.982646 180)
		(property "Reference" "C25W58"
			(at 0.8382 -0.67818 180)
			(unlocked yes)
			(layer "B.SilkS")
			(effects
				(font
					(size 0.4064 0.254)
					(thickness 0.1524)
				)
				(justify left mirror)
			)
		)
		(property "Value" ""
			(at 0 0 0)
			(layer "B.Fab")
			(effects
				(font
					(size 1.27 1.27)
				)
				(justify mirror)
			)
		)
		(duplicate_pad_numbers_are_jumpers no)
		(fp_poly
			(pts
				(xy -0.3048 -0.1016) (xy -0.3048 0.9906) (xy 0.3048 0.9906) (xy 0.3048 -0.1016)
			)
			(stroke
				(width 0)
				(type default)
			)
			(fill no)
			(layer "B.CrtYd")
		)
		(fp_line
			(start 0.3048 0.9906)
			(end -0.3048 0.9906)
			(stroke
				(width 0.1)
				(type default)
			)
			(layer "B.Fab")
		)
		(fp_line
			(start 0.3048 -0.1016)
			(end 0.3048 0.9906)
			(stroke
				(width 0.1)
				(type default)
			)
			(layer "B.Fab")
		)
		(fp_line
			(start -0.3048 0.9906)
			(end -0.3048 -0.1016)
			(stroke
				(width 0.1)
				(type default)
			)
			(layer "B.Fab")
		)
		(fp_line
			(start -0.3048 -0.1016)
			(end 0.3048 -0.1016)
			(stroke
				(width 0.1)
				(type default)
			)
			(layer "B.Fab")
		)
		(pad "1" smd rect
			(at 0 0)
			(size 0.508 0.508)
			(layers "B.Cu" "B.Mask" "B.Paste")
			(net "VCC_PA_3V3")
		)
		(pad "2" smd rect
			(at 0 0.889)
			(size 0.508 0.508)
			(layers "B.Cu" "B.Mask" "B.Paste")
			(net "GND")
		)
		(zone
			(layer "B.Cu")
			(hatch none 0.5)
			(connect_pads
				(clearance 0)
			)
			(min_thickness 0.25)
			(keepout
				(tracks not_allowed)
				(vias allowed)
				(pads allowed)
				(copperpour not_allowed)
				(footprints allowed)
			)
			(placement
				(enabled no)
				(sheetname "")
			)
			(fill
				(thermal_gap 0.5)
				(thermal_bridge_width 0.5)
				(island_removal_mode 0)
			)
			(polygon
				(pts
					(xy 423.133774 -41.617646) (xy 423.641774 -41.617646) (xy 423.641774 -41.236646) (xy 423.133774 -41.236646)
				)
			)
		)
		(zone
			(layer "B.Cu")
			(hatch none 0.5)
			(connect_pads
				(clearance 0)
			)
			(min_thickness 0.25)
			(keepout
				(tracks allowed)
				(vias not_allowed)
				(pads allowed)
				(copperpour not_allowed)
				(footprints allowed)
			)
			(placement
				(enabled no)
				(sheetname "")
			)
			(fill
				(thermal_gap 0.5)
				(thermal_bridge_width 0.5)
				(island_removal_mode 0)
			)
			(polygon
				(pts
					(xy 423.133774 -41.236646) (xy 423.641774 -41.236646) (xy 423.641774 -41.617646) (xy 423.133774 -41.617646)
				)
			)
		)
	)
	(footprint ""
		(layer "B.Cu")
		(at 370.986558 -40.617648 90)
		(property "Reference" "R2T57"
			(at 0 0 90)
			(layer "B.SilkS")
			(hide yes)
			(effects
				(font
					(size 1.27 1.27)
				)
				(justify mirror)
			)
		)
		(property "Value" ""
			(at 0 0 90)
			(layer "B.Fab")
			(effects
				(font
					(size 1.27 1.27)
				)
				(justify mirror)
			)
		)
		(duplicate_pad_numbers_are_jumpers no)
		(fp_poly
			(pts
				(xy 0.2794 -0.1016) (xy -0.2794 -0.1016) (xy -0.2794 0.9906) (xy 0.2794 0.9906)
			)
			(stroke
				(width 0)
				(type default)
			)
			(fill no)
			(layer "B.CrtYd")
		)
		(fp_line
			(start 0.2794 -0.1016)
			(end 0.2794 0.9906)
			(stroke
				(width 0.1)
				(type default)
			)
			(layer "B.Fab")
		)
		(fp_line
			(start -0.2794 -0.1016)
			(end 0.2794 -0.1016)
			(stroke
				(width 0.1)
				(type default)
			)
			(layer "B.Fab")
		)
		(fp_line
			(start 0.2794 0.9906)
			(end -0.2794 0.9906)
			(stroke
				(width 0.1)
				(type default)
			)
			(layer "B.Fab")
		)
		(fp_line
			(start -0.2794 0.9906)
			(end -0.2794 -0.1016)
			(stroke
				(width 0.1)
				(type default)
			)
			(layer "B.Fab")
		)
		(pad "1" smd rect
			(at 0 0 270)
			(size 0.508 0.508)
			(layers "B.Cu" "B.Mask" "B.Paste")
			(net "H_CPU_ERR0_PCH_N")
		)
		(pad "2" smd rect
			(at 0 0.889 270)
			(size 0.508 0.508)
			(layers "B.Cu" "B.Mask" "B.Paste")
			(net "H_CPU_ERR0_GTL_R_N")
		)
		(zone
			(layer "B.Cu")
			(hatch none 0.5)
			(connect_pads
				(clearance 0)
			)
			(min_thickness 0.25)
			(keepout
				(tracks allowed)
				(vias not_allowed)
				(pads allowed)
				(copperpour not_allowed)
				(footprints allowed)
			)
			(placement
				(enabled no)
				(sheetname "")
			)
			(fill
				(thermal_gap 0.5)
				(thermal_bridge_width 0.5)
				(island_removal_mode 0)
			)
			(polygon
				(pts
					(xy 371.240558 -40.871648) (xy 371.240558 -40.363648) (xy 371.621558 -40.363648) (xy 371.621558 -40.871648)
				)
			)
		)
		(zone
			(layer "B.Cu")
			(hatch none 0.5)
			(connect_pads
				(clearance 0)
			)
			(min_thickness 0.25)
			(keepout
				(tracks not_allowed)
				(vias allowed)
				(pads allowed)
				(copperpour not_allowed)
				(footprints allowed)
			)
			(placement
				(enabled no)
				(sheetname "")
			)
			(fill
				(thermal_gap 0.5)
				(thermal_bridge_width 0.5)
				(island_removal_mode 0)
			)
			(polygon
				(pts
					(xy 371.621558 -40.871648) (xy 371.621558 -40.363648) (xy 371.240558 -40.363648) (xy 371.240558 -40.871648)
				)
			)
		)
	)
	(footprint ""
		(layer "B.Cu")
		(at 382.27 -87.3125 180)
		(property "Reference" "R7D6"
			(at 0 0 0)
			(layer "B.SilkS")
			(hide yes)
			(effects
				(font
					(size 1.27 1.27)
				)
				(justify mirror)
			)
		)
		(property "Value" ""
			(at 0 0 0)
			(layer "B.Fab")
			(effects
				(font
					(size 1.27 1.27)
				)
				(justify mirror)
			)
		)
		(duplicate_pad_numbers_are_jumpers no)
		(fp_poly
			(pts
				(xy 0.2794 -0.1016) (xy -0.2794 -0.1016) (xy -0.2794 0.9906) (xy 0.2794 0.9906)
			)
			(stroke
				(width 0)
				(type default)
			)
			(fill no)
			(layer "B.CrtYd")
		)
		(fp_line
			(start 0.2794 0.9906)
			(end -0.2794 0.9906)
			(stroke
				(width 0.1)
				(type default)
			)
			(layer "B.Fab")
		)
		(fp_line
			(start 0.2794 -0.1016)
			(end 0.2794 0.9906)
			(stroke
				(width 0.1)
				(type default)
			)
			(layer "B.Fab")
		)
		(fp_line
			(start -0.2794 0.9906)
			(end -0.2794 -0.1016)
			(stroke
				(width 0.1)
				(type default)
			)
			(layer "B.Fab")
		)
		(fp_line
			(start -0.2794 -0.1016)
			(end 0.2794 -0.1016)
			(stroke
				(width 0.1)
				(type default)
			)
			(layer "B.Fab")
		)
		(pad "1" smd rect
			(at 0 0)
			(size 0.508 0.508)
			(layers "B.Cu" "B.Mask" "B.Paste")
			(net "P3V3_STBY")
		)
		(pad "2" smd rect
			(at 0 0.889)
			(size 0.508 0.508)
			(layers "B.Cu" "B.Mask" "B.Paste")
			(net "FM_BMC_READY_N")
		)
		(zone
			(layer "B.Cu")
			(hatch none 0.5)
			(connect_pads
				(clearance 0)
			)
			(min_thickness 0.25)
			(keepout
				(tracks not_allowed)
				(vias allowed)
				(pads allowed)
				(copperpour not_allowed)
				(footprints allowed)
			)
			(placement
				(enabled no)
				(sheetname "")
			)
			(fill
				(thermal_gap 0.5)
				(thermal_bridge_width 0.5)
				(island_removal_mode 0)
			)
			(polygon
				(pts
					(xy 382.016 -87.9475) (xy 382.524 -87.9475) (xy 382.524 -87.5665) (xy 382.016 -87.5665)
				)
			)
		)
		(zone
			(layer "B.Cu")
			(hatch none 0.5)
			(connect_pads
				(clearance 0)
			)
			(min_thickness 0.25)
			(keepout
				(tracks allowed)
				(vias not_allowed)
				(pads allowed)
				(copperpour not_allowed)
				(footprints allowed)
			)
			(placement
				(enabled no)
				(sheetname "")
			)
			(fill
				(thermal_gap 0.5)
				(thermal_bridge_width 0.5)
				(island_removal_mode 0)
			)
			(polygon
				(pts
					(xy 382.016 -87.5665) (xy 382.524 -87.5665) (xy 382.524 -87.9475) (xy 382.016 -87.9475)
				)
			)
		)
	)
)
